# S9S_MB_2U (Grand Teton) — schematic netlist excerpt (pin names and nets, part order shuffled) for the footprints in the layout excerpt that follows; sources: Cadence DE-HDL packaged netlist, KiCad conversion of 03242023_DA0F0TMBIJ0_F0T_Motherboard_J_brd_V01_OCP.brd

C476  Q_CAP  47UF 4V 20% X6S  pkg C0805  page 79 : A = PVCCFA_EHV_FIVRA_CPU1 ; B = GND
R4097  Q_RES  10K 1% CHIP  pkg 0402LF  page 183 : A = PD_PCH_GPPC_A_15 ; B = GND
C2035  Q_CAP  1UF 25V 10% X6S  pkg C0402  page 152 : A = P3V3_AUX_USB_HUB ; B = GND

(kicad_pcb
	(version 20260206)
	(generator "pcbnew")
	(generator_version "10.0")
	(general
		(thickness 1.6)
		(legacy_teardrops no)
	)
	(paper "A4")
	(title_block
		(title "03242023_DA0F0TMBIJ0_F0T_Motherboard_J_brd_V01_OCP.brd")
		(comment 1 "Grand Teton / footprints 5902-5904 of 6105")
	)
	(layers
		(0 "F.Cu" signal "TOP")
		(4 "In1.Cu" signal "GND")
		(6 "In2.Cu" signal "IN1")
		(8 "In3.Cu" signal "GND1")
		(10 "In4.Cu" signal "IN2")
		(12 "In5.Cu" signal "GND2")
		(14 "In6.Cu" signal "IN3")
		(16 "In7.Cu" signal "GND3")
		(18 "In8.Cu" signal "VCC")
		(20 "In9.Cu" signal "VCC1")
		(22 "In10.Cu" signal "GND4")
		(24 "In11.Cu" signal "IN4")
		(26 "In12.Cu" signal "GND5")
		(28 "In13.Cu" signal "IN5")
		(30 "In14.Cu" signal "GND6")
		(32 "In15.Cu" signal "IN6")
		(34 "In16.Cu" signal "GND7")
		(2 "B.Cu" signal "BOTTOM")
		(9 "F.Adhes" user "F.Adhesive")
		(11 "B.Adhes" user "B.Adhesive")
		(13 "F.Paste" user "Package Geometry/Pastemask Top")
		(15 "B.Paste" user "Package Geometry/Pastemask Bottom")
		(5 "F.SilkS" user "Ref Des/Silkscreen Top")
		(7 "B.SilkS" user "Ref Des/Silkscreen Bottom")
		(1 "F.Mask" user "Board Geometry/Soldermask Top")
		(3 "B.Mask" user "Board Geometry/Soldermask Bottom")
		(17 "Dwgs.User" user "User.Drawings")
		(19 "Cmts.User" user "User.Comments")
		(21 "Eco1.User" user "User.Eco1")
		(23 "Eco2.User" user "User.Eco2")
		(25 "Edge.Cuts" user "Board Geometry/Outline")
		(27 "Margin" user)
		(31 "F.CrtYd" user "Package Geometry/Place Bound Top")
		(29 "B.CrtYd" user "Package Geometry/Place Bound Bottom")
		(35 "F.Fab" user "Ref Des/Assembly Top")
		(33 "B.Fab" user "Ref Des/Assembly Bottom")
	)
	(footprint ""
		(layer "B.Cu")
		(at 331.09408 -25.212548)
		(property "Reference" "R4097"
			(at 0 0 0)
			(layer "B.SilkS")
			(hide yes)
			(effects
				(font
					(size 1.27 1.27)
				)
				(justify mirror)
			)
		)
		(property "Value" ""
			(at 0 0 0)
			(layer "B.Fab")
			(effects
				(font
					(size 1.27 1.27)
				)
				(justify mirror)
			)
		)
		(duplicate_pad_numbers_are_jumpers no)
		(fp_line
			(start -0.7874 -0.4064)
			(end -0.7874 0.4064)
			(stroke
				(width 0.1524)
				(type default)
			)
			(layer "B.SilkS")
		)
		(fp_line
			(start -0.7874 0.4064)
			(end 0.7874 0.4064)
			(stroke
				(width 0.1524)
				(type default)
			)
			(layer "B.SilkS")
		)
		(fp_line
			(start 0.7874 -0.4064)
			(end -0.7874 -0.4064)
			(stroke
				(width 0.1524)
				(type default)
			)
			(layer "B.SilkS")
		)
		(fp_line
			(start 0.7874 0.4064)
			(end 0.7874 -0.4064)
			(stroke
				(width 0.1524)
				(type default)
			)
			(layer "B.SilkS")
		)
		(fp_line
			(start -0.67945 -0.3048)
			(end -0.67945 0.3048)
			(stroke
				(width 0.1)
				(type default)
			)
			(layer "B.Fab")
		)
		(fp_line
			(start -0.67945 0.3048)
			(end -0.120396 0.3048)
			(stroke
				(width 0.1)
				(type default)
			)
			(layer "B.Fab")
		)
		(fp_line
			(start -0.12065 -0.3048)
			(end -0.67945 -0.3048)
			(stroke
				(width 0.1)
				(type default)
			)
			(layer "B.Fab")
		)
		(fp_line
			(start -0.12065 -0.2794)
			(end -0.12065 -0.3048)
			(stroke
				(width 0.1)
				(type default)
			)
			(layer "B.Fab")
		)
		(fp_line
			(start -0.120396 0.2794)
			(end 0.12065 0.2794)
			(stroke
				(width 0.1)
				(type default)
			)
			(layer "B.Fab")
		)
		(fp_line
			(start -0.120396 0.3048)
			(end -0.120396 0.2794)
			(stroke
				(width 0.1)
				(type default)
			)
			(layer "B.Fab")
		)
		(fp_line
			(start 0.12065 -0.305054)
			(end 0.12065 -0.2794)
			(stroke
				(width 0.1)
				(type default)
			)
			(layer "B.Fab")
		)
		(fp_line
			(start 0.12065 -0.2794)
			(end -0.12065 -0.2794)
			(stroke
				(width 0.1)
				(type default)
			)
			(layer "B.Fab")
		)
		(fp_line
			(start 0.12065 0.2794)
			(end 0.12065 0.3048)
			(stroke
				(width 0.1)
				(type default)
			)
			(layer "B.Fab")
		)
		(fp_line
			(start 0.12065 0.3048)
			(end 0.67945 0.3048)
			(stroke
				(width 0.1)
				(type default)
			)
			(layer "B.Fab")
		)
		(fp_line
			(start 0.67945 -0.305054)
			(end 0.12065 -0.305054)
			(stroke
				(width 0.1)
				(type default)
			)
			(layer "B.Fab")
		)
		(fp_line
			(start 0.67945 0.3048)
			(end 0.67945 -0.305054)
			(stroke
				(width 0.1)
				(type default)
			)
			(layer "B.Fab")
		)
		(pad "1" smd circle
			(at 0.40005 0 180)
			(size 0 0)
			(layers "B.Cu" "B.Mask" "B.Paste")
			(net "PD_PCH_GPPC_A_15")
		)
		(pad "2" smd circle
			(at -0.40005 0 180)
			(size 0 0)
			(layers "B.Cu" "B.Mask" "B.Paste")
			(net "GND")
		)
	)
	(footprint ""
		(layer "B.Cu")
		(at 160.89249 -258.399534 -90)
		(property "Reference" "C476"
			(at 0 0 90)
			(layer "B.SilkS")
			(hide yes)
			(effects
				(font
					(size 1.27 1.27)
				)
				(justify mirror)
			)
		)
		(property "Value" ""
			(at 0 0 90)
			(layer "B.Fab")
			(effects
				(font
					(size 1.27 1.27)
				)
				(justify mirror)
			)
		)
		(duplicate_pad_numbers_are_jumpers no)
		(fp_line
			(start -1.524 0.762)
			(end 1.524 0.762)
			(stroke
				(width 0.1524)
				(type default)
			)
			(layer "B.SilkS")
		)
		(fp_line
			(start 1.524 0.762)
			(end 1.524 -0.762)
			(stroke
				(width 0.1524)
				(type default)
			)
			(layer "B.SilkS")
		)
		(fp_line
			(start -1.524 -0.762)
			(end -1.524 0.762)
			(stroke
				(width 0.1524)
				(type default)
			)
			(layer "B.SilkS")
		)
		(fp_line
			(start 1.524 -0.762)
			(end -1.524 -0.762)
			(stroke
				(width 0.1524)
				(type default)
			)
			(layer "B.SilkS")
		)
		(fp_line
			(start -1.1049 0.724916)
			(end -1.1049 -0.724916)
			(stroke
				(width 0.1)
				(type default)
			)
			(layer "B.Fab")
		)
		(fp_line
			(start 1.1049 0.724916)
			(end -1.1049 0.724916)
			(stroke
				(width 0.1)
				(type default)
			)
			(layer "B.Fab")
		)
		(fp_line
			(start -1.1049 -0.724916)
			(end 1.1049 -0.724916)
			(stroke
				(width 0.1)
				(type default)
			)
			(layer "B.Fab")
		)
		(fp_line
			(start 1.1049 -0.724916)
			(end 1.1049 0.724916)
			(stroke
				(width 0.1)
				(type default)
			)
			(layer "B.Fab")
		)
		(pad "1" smd rect
			(at 0.889 0 270)
			(size 1.016 1.27)
			(layers "B.Cu" "B.Mask" "B.Paste")
			(net "PVCCFA_EHV_FIVRA_CPU1")
		)
		(pad "2" smd rect
			(at -0.889 0 270)
			(size 1.016 1.27)
			(layers "B.Cu" "B.Mask" "B.Paste")
			(net "GND")
		)
	)
	(footprint ""
		(layer "B.Cu")
		(at 13.649452 -101.21138 90)
		(property "Reference" "C2035"
			(at 0 0 90)
			(layer "B.SilkS")
			(hide yes)
			(effects
				(font
					(size 1.27 1.27)
				)
				(justify mirror)
			)
		)
		(property "Value" ""
			(at 0 0 90)
			(layer "B.Fab")
			(effects
				(font
					(size 1.27 1.27)
				)
				(justify mirror)
			)
		)
		(duplicate_pad_numbers_are_jumpers no)
		(fp_line
			(start 0.7874 -0.4064)
			(end -0.7874 -0.4064)
			(stroke
				(width 0.1524)
				(type default)
			)
			(layer "B.SilkS")
		)
		(fp_line
			(start -0.7874 -0.4064)
			(end -0.7874 0.4064)
			(stroke
				(width 0.1524)
				(type default)
			)
			(layer "B.SilkS")
		)
		(fp_line
			(start 0.7874 0.4064)
			(end 0.7874 -0.4064)
			(stroke
				(width 0.1524)
				(type default)
			)
			(layer "B.SilkS")
		)
		(fp_line
			(start -0.7874 0.4064)
			(end 0.7874 0.4064)
			(stroke
				(width 0.1524)
				(type default)
			)
			(layer "B.SilkS")
		)
		(fp_line
			(start 0.67945 -0.305054)
			(end 0.12065 -0.305054)
			(stroke
				(width 0.1)
				(type default)
			)
			(layer "B.Fab")
		)
		(fp_line
			(start 0.12065 -0.305054)
			(end 0.12065 -0.2794)
			(stroke
				(width 0.1)
				(type default)
			)
			(layer "B.Fab")
		)
		(fp_line
			(start -0.12065 -0.3048)
			(end -0.67945 -0.3048)
			(stroke
				(width 0.1)
				(type default)
			)
			(layer "B.Fab")
		)
		(fp_line
			(start -0.67945 -0.3048)
			(end -0.67945 0.3048)
			(stroke
				(width 0.1)
				(type default)
			)
			(layer "B.Fab")
		)
		(fp_line
			(start 0.12065 -0.2794)
			(end -0.12065 -0.2794)
			(stroke
				(width 0.1)
				(type default)
			)
			(layer "B.Fab")
		)
		(fp_line
			(start -0.12065 -0.2794)
			(end -0.12065 -0.3048)
			(stroke
				(width 0.1)
				(type default)
			)
			(layer "B.Fab")
		)
		(fp_line
			(start 0.12065 0.2794)
			(end 0.12065 0.3048)
			(stroke
				(width 0.1)
				(type default)
			)
			(layer "B.Fab")
		)
		(fp_line
			(start -0.120396 0.2794)
			(end 0.12065 0.2794)
			(stroke
				(width 0.1)
				(type default)
			)
			(layer "B.Fab")
		)
		(fp_line
			(start 0.67945 0.3048)
			(end 0.67945 -0.305054)
			(stroke
				(width 0.1)
				(type default)
			)
			(layer "B.Fab")
		)
		(fp_line
			(start 0.12065 0.3048)
			(end 0.67945 0.3048)
			(stroke
				(width 0.1)
				(type default)
			)
			(layer "B.Fab")
		)
		(fp_line
			(start -0.120396 0.3048)
			(end -0.120396 0.2794)
			(stroke
				(width 0.1)
				(type default)
			)
			(layer "B.Fab")
		)
		(fp_line
			(start -0.67945 0.3048)
			(end -0.120396 0.3048)
			(stroke
				(width 0.1)
				(type default)
			)
			(layer "B.Fab")
		)
		(pad "1" smd circle
			(at 0.40005 0 270)
			(size 0 0)
			(layers "B.Cu" "B.Mask" "B.Paste")
			(net "P3V3_AUX_USB_HUB")
		)
		(pad "2" smd circle
			(at -0.40005 0 270)
			(size 0 0)
			(layers "B.Cu" "B.Mask" "B.Paste")
			(net "GND")
		)
	)
)
